# 13919-SA_Riser Card_equal length_1120_1.xlsx — PCIE_10G (si-constraints)
| SPEC |  |  |  |
| Length match | 5 mil |  |  |
| NET | L1 | Length match <1 mil | Length match each other <100mil |
| P2E_CPU_ETH10G_RX_DN11 | 615.5 | OK | OK |
| P2E_CPU_ETH10G_RX_DP11 | 615.22 |  |  |
| P2E_CPU_ETH10G_RX_DN10 | 614.99 | OK |  |
| P2E_CPU_ETH10G_RX_DP10 | 614.09 |  |  |
| P2E_CPU_ETH10G_RX_DN9 | 615.20000000000005 | OK |  |
| P2E_CPU_ETH10G_RX_DP9 | 615.70000000000005 |  |  |
| P2E_CPU_ETH10G_RX_DN8 | 615.45000000000005 | OK |  |
| P2E_CPU_ETH10G_RX_DP8 | 615.16999999999996 |  |  |
| P2E_CPU_ETH10G_TX_DN11 | 854.55 | OK | OK |
| P2E_CPU_ETH10G_TX_DP11 | 854.65 |  |  |
| P2E_CPU_ETH10G_TX_DN10 | 826.01 | OK |  |
| P2E_CPU_ETH10G_TX_DP10 | 826.07 |  |  |
| P2E_CPU_ETH10G_TX_DN8 | 825.92 | OK |  |
| P2E_CPU_ETH10G_TX_DP8 | 826.09 |  |  |
| P2E_CPU_ETH10G_TX_DN9 | 825.95 | OK |  |
| P2E_CPU_ETH10G_TX_DP9 | 826.06 |  |  |
